(kicad_pcb
	(version 20260206)
	(generator "pcbnew")
	(generator_version "10.0")
	(general
		(thickness 1.6)
		(legacy_teardrops no)
	)
	(paper "A4")
	(title_block
		(title "Wiwynn_Tioga_Pass_MB.brd")
		(comment 1 "Tioga Pass / footprint 190 of 4770 (U2D1), pads 2625-2734 of 3647")
	)
	(layers
		(0 "F.Cu" signal "TOP")
		(4 "In1.Cu" signal "L2GND")
		(6 "In2.Cu" signal "L3")
		(8 "In3.Cu" signal "L4GND")
		(10 "In4.Cu" signal "L5")
		(12 "In5.Cu" signal "L6GND")
		(14 "In6.Cu" signal "L7VCC")
		(16 "In7.Cu" signal "L8VCC")
		(18 "In8.Cu" signal "L9GND")
		(20 "In9.Cu" signal "L10")
		(22 "In10.Cu" signal "L11GND")
		(24 "In11.Cu" signal "L12")
		(26 "In12.Cu" signal "L13GND")
		(2 "B.Cu" signal "BOTTOM")
		(9 "F.Adhes" user "F.Adhesive")
		(11 "B.Adhes" user "B.Adhesive")
		(13 "F.Paste" user "Package Geometry/Pastemask Top")
		(15 "B.Paste" user "Package Geometry/Pastemask Bottom")
		(5 "F.SilkS" user "Ref Des/Silkscreen Top")
		(7 "B.SilkS" user "Ref Des/Silkscreen Bottom")
		(1 "F.Mask" user "Board Geometry/Soldermask Top")
		(3 "B.Mask" user "Board Geometry/Soldermask Bottom")
		(17 "Dwgs.User" user "User.Drawings")
		(19 "Cmts.User" user "User.Comments")
		(21 "Eco1.User" user "User.Eco1")
		(23 "Eco2.User" user "User.Eco2")
		(25 "Edge.Cuts" user "Board Geometry/Outline")
		(27 "Margin" user)
		(31 "F.CrtYd" user "Package Geometry/Place Bound Top")
		(29 "B.CrtYd" user "Package Geometry/Place Bound Bottom")
		(35 "F.Fab" user "Ref Des/Assembly Top")
		(33 "B.Fab" user "Ref Des/Assembly Bottom")
	)
	(footprint ""
		(layer "F.Cu")
		(at 104.99979 -76.550012 180)
		(property "Reference" "U2D1"
			(at 25.19299 30.484318 0)
			(unlocked yes)
			(layer "F.SilkS")
			(effects
				(font
					(size 0.7874 0.5842)
					(thickness 0.1524)
				)
			)
		)
		(property "Value" ""
			(at 0 0 180)
			(layer "F.Fab")
			(effects
				(font
					(size 1.27 1.27)
				)
			)
		)
		(duplicate_pad_numbers_are_jumpers no)
		(pad "DU36" smd circle
			(at -7.202932 22.445726)
			(size 0.4318 0.4318)
			(layers "F.Cu" "F.Mask" "F.Paste")
			(net "M_K_DQ<41>")
		)
		(pad "DU38" smd circle
			(at -5.485892 22.445726)
			(size 0.4318 0.4318)
			(layers "F.Cu" "F.Mask" "F.Paste")
			(net "GND")
		)
		(pad "DU40" smd circle
			(at -3.769106 22.445726)
			(size 0.4318 0.4318)
			(layers "F.Cu" "F.Mask" "F.Paste")
			(net "M_L_DQ<39>")
		)
		(pad "DU42" smd circle
			(at -2.052066 22.445726)
			(size 0.4318 0.4318)
			(layers "F.Cu" "F.Mask" "F.Paste")
			(net "M_L_DQ<32>")
		)
		(pad "DU44" smd circle
			(at 1.193546 20.645628)
			(size 0.508 0.508)
			(layers "F.Cu" "F.Mask" "F.Paste")
			(net "TP_CPU1_RSVD_26")
		)
		(pad "DU46" smd circle
			(at 2.910586 20.645628)
			(size 0.4318 0.4318)
			(layers "F.Cu" "F.Mask" "F.Paste")
			(net "PVDDQ_KLM")
		)
		(pad "DU48" smd circle
			(at 4.627626 20.645628)
			(size 0.4318 0.4318)
			(layers "F.Cu" "F.Mask" "F.Paste")
			(net "PVDDQ_KLM")
		)
		(pad "DU50" smd circle
			(at 6.344412 20.645628)
			(size 0.4318 0.4318)
			(layers "F.Cu" "F.Mask" "F.Paste")
			(net "PVDDQ_KLM")
		)
		(pad "DU52" smd circle
			(at 8.061452 20.645628)
			(size 0.4318 0.4318)
			(layers "F.Cu" "F.Mask" "F.Paste")
			(net "PVDDQ_KLM")
		)
		(pad "DU54" smd circle
			(at 9.778492 20.645628)
			(size 0.4318 0.4318)
			(layers "F.Cu" "F.Mask" "F.Paste")
			(net "PVDDQ_KLM")
		)
		(pad "DU56" smd circle
			(at 11.495532 20.645628)
			(size 0.4318 0.4318)
			(layers "F.Cu" "F.Mask" "F.Paste")
			(net "PVDDQ_KLM")
		)
		(pad "DU58" smd circle
			(at 13.212572 20.645628)
			(size 0.4318 0.4318)
			(layers "F.Cu" "F.Mask" "F.Paste")
			(net "PVDDQ_KLM")
		)
		(pad "DU60" smd circle
			(at 14.929612 20.645628)
			(size 0.4318 0.4318)
			(layers "F.Cu" "F.Mask" "F.Paste")
			(net "PVDDQ_KLM")
		)
		(pad "DU62" smd circle
			(at 16.646398 20.645628)
			(size 0.4318 0.4318)
			(layers "F.Cu" "F.Mask" "F.Paste")
			(net "PVDDQ_KLM")
		)
		(pad "DU64" smd circle
			(at 18.363438 20.645628)
			(size 0.4318 0.4318)
			(layers "F.Cu" "F.Mask" "F.Paste")
			(net "PVDDQ_KLM")
		)
		(pad "DU66" smd circle
			(at 20.080478 20.645628)
			(size 0.4318 0.4318)
			(layers "F.Cu" "F.Mask" "F.Paste")
			(net "M_L_ECC<6>")
		)
		(pad "DU68" smd circle
			(at 21.797518 20.645628)
			(size 0.4318 0.4318)
			(layers "F.Cu" "F.Mask" "F.Paste")
			(net "M_L_ECC<4>")
		)
		(pad "DU70" smd circle
			(at 23.514558 20.645628)
			(size 0.4318 0.4318)
			(layers "F.Cu" "F.Mask" "F.Paste")
			(net "GND")
		)
		(pad "DU72" smd circle
			(at 25.231598 20.645628)
			(size 0.4318 0.4318)
			(layers "F.Cu" "F.Mask" "F.Paste")
			(net "GND")
		)
		(pad "DU74" smd circle
			(at 26.948384 20.645628)
			(size 0.4318 0.4318)
			(layers "F.Cu" "F.Mask" "F.Paste")
			(net "M_K_DQ<31>")
		)
		(pad "DU76" smd circle
			(at 28.665424 20.645628)
			(size 0.4318 0.4318)
			(layers "F.Cu" "F.Mask" "F.Paste")
			(net "M_K_DQ<25>")
		)
		(pad "DU78" smd circle
			(at 30.382464 20.645628)
			(size 0.4318 0.4318)
			(layers "F.Cu" "F.Mask" "F.Paste")
			(net "GND")
		)
		(pad "DU80" smd circle
			(at 32.099504 20.645628)
			(size 0.4318 0.4318)
			(layers "F.Cu" "F.Mask" "F.Paste")
			(net "GND")
		)
		(pad "DU82" smd circle
			(at 33.816544 20.645628)
			(size 0.4318 0.4318)
			(layers "F.Cu" "F.Mask" "F.Paste")
			(net "GND")
		)
		(pad "DU84" smd circle
			(at 35.533584 20.645628)
			(size 0.4318 0.4318)
			(layers "F.Cu" "F.Mask" "F.Paste")
			(net "GND")
		)
		(pad "DV3" smd circle
			(at -35.533584 22.940772)
			(size 0.4318 0.4318)
			(layers "F.Cu" "F.Mask" "F.Paste")
			(net "TP_P3E_CPU1_PE1_RSR3_TXN<9>")
		)
		(pad "DV5" smd circle
			(at -33.816544 22.940772)
			(size 0.4318 0.4318)
			(layers "F.Cu" "F.Mask" "F.Paste")
			(net "TP_P3E_CPU1_PE1_RSR3_TXP<11>")
		)
		(pad "DV7" smd circle
			(at -32.099504 22.940772)
			(size 0.4318 0.4318)
			(layers "F.Cu" "F.Mask" "F.Paste")
			(net "TP_P3E_CPU1_PE1_RSR3_TXN<12>")
		)
		(pad "DV9" smd circle
			(at -30.382464 22.940772)
			(size 0.4318 0.4318)
			(layers "F.Cu" "F.Mask" "F.Paste")
			(net "P3E_CPU1_PE3_MP_TXP<5>")
		)
		(pad "DV11" smd circle
			(at -28.665424 22.940772)
			(size 0.4318 0.4318)
			(layers "F.Cu" "F.Mask" "F.Paste")
			(net "PVCCIO_CPU1")
		)
		(pad "DV13" smd circle
			(at -26.948384 22.940772)
			(size 0.4318 0.4318)
			(layers "F.Cu" "F.Mask" "F.Paste")
			(net "TP_P3E_CPU1_PE1_RSR3_RXN<12>")
		)
		(pad "DV15" smd circle
			(at -25.231598 22.940772)
			(size 0.4318 0.4318)
			(layers "F.Cu" "F.Mask" "F.Paste")
			(net "TP_P3E_CPU1_PE1_RSR3_RXP<14>")
		)
		(pad "DV17" smd circle
			(at -23.514558 22.940772)
			(size 0.4318 0.4318)
			(layers "F.Cu" "F.Mask" "F.Paste")
			(net "P3E_CPU1_PE3_MP_RXP<2>")
		)
		(pad "DV19" smd circle
			(at -21.797518 22.940772)
			(size 0.4318 0.4318)
			(layers "F.Cu" "F.Mask" "F.Paste")
			(net "GND")
		)
		(pad "DV21" smd circle
			(at -20.080478 22.940772)
			(size 0.4318 0.4318)
			(layers "F.Cu" "F.Mask" "F.Paste")
			(net "GND")
		)
		(pad "DV23" smd circle
			(at -18.363438 22.940772)
			(size 0.4318 0.4318)
			(layers "F.Cu" "F.Mask" "F.Paste")
			(net "M_K_DQS_DN<7>")
		)
		(pad "DV25" smd circle
			(at -16.646398 22.940772)
			(size 0.4318 0.4318)
			(layers "F.Cu" "F.Mask" "F.Paste")
			(net "GND")
		)
		(pad "DV27" smd circle
			(at -14.929612 22.940772)
			(size 0.4318 0.4318)
			(layers "F.Cu" "F.Mask" "F.Paste")
			(net "GND")
		)
		(pad "DV29" smd circle
			(at -13.212572 22.940772)
			(size 0.4318 0.4318)
			(layers "F.Cu" "F.Mask" "F.Paste")
			(net "M_K_DQS_DN<6>")
		)
		(pad "DV31" smd circle
			(at -11.495532 22.940772)
			(size 0.4318 0.4318)
			(layers "F.Cu" "F.Mask" "F.Paste")
			(net "GND")
		)
		(pad "DV33" smd circle
			(at -9.778492 22.940772)
			(size 0.4318 0.4318)
			(layers "F.Cu" "F.Mask" "F.Paste")
			(net "GND")
		)
		(pad "DV35" smd circle
			(at -8.061452 22.940772)
			(size 0.4318 0.4318)
			(layers "F.Cu" "F.Mask" "F.Paste")
			(net "M_K_DQS_DN<5>")
		)
		(pad "DV37" smd circle
			(at -6.344412 22.940772)
			(size 0.4318 0.4318)
			(layers "F.Cu" "F.Mask" "F.Paste")
			(net "GND")
		)
		(pad "DV39" smd circle
			(at -4.627626 22.940772)
			(size 0.4318 0.4318)
			(layers "F.Cu" "F.Mask" "F.Paste")
			(net "GND")
		)
		(pad "DV41" smd circle
			(at -2.910586 22.940772)
			(size 0.4318 0.4318)
			(layers "F.Cu" "F.Mask" "F.Paste")
			(net "M_L_DQS_DN<4>")
		)
		(pad "DV45" smd circle
			(at 2.052066 21.140674)
			(size 0.4318 0.4318)
			(layers "F.Cu" "F.Mask" "F.Paste")
			(net "M_K_CS_N<6>")
		)
		(pad "DV47" smd circle
			(at 3.769106 21.140674)
			(size 0.4318 0.4318)
			(layers "F.Cu" "F.Mask" "F.Paste")
			(net "M_K_C<2>")
		)
		(pad "DV49" smd circle
			(at 5.485892 21.140674)
			(size 0.4318 0.4318)
			(layers "F.Cu" "F.Mask" "F.Paste")
			(net "M_K_MA<15>")
		)
		(pad "DV51" smd circle
			(at 7.202932 21.140674)
			(size 0.4318 0.4318)
			(layers "F.Cu" "F.Mask" "F.Paste")
			(net "M_L_CS_N<0>")
		)
		(pad "DV53" smd circle
			(at 8.919972 21.140674)
			(size 0.4318 0.4318)
			(layers "F.Cu" "F.Mask" "F.Paste")
			(net "M_L_PAR")
		)
		(pad "DV55" smd circle
			(at 10.637012 21.140674)
			(size 0.4318 0.4318)
			(layers "F.Cu" "F.Mask" "F.Paste")
			(net "M_L_BA<1>")
		)
		(pad "DV57" smd circle
			(at 12.354052 21.140674)
			(size 0.4318 0.4318)
			(layers "F.Cu" "F.Mask" "F.Paste")
			(net "M_L_MA<2>")
		)
		(pad "DV59" smd circle
			(at 14.071092 21.140674)
			(size 0.4318 0.4318)
			(layers "F.Cu" "F.Mask" "F.Paste")
			(net "M_L_MA<9>")
		)
		(pad "DV61" smd circle
			(at 15.787878 21.140674)
			(size 0.4318 0.4318)
			(layers "F.Cu" "F.Mask" "F.Paste")
			(net "TP_CPU1_RSVD_25")
		)
		(pad "DV63" smd circle
			(at 17.504918 21.140674)
			(size 0.4318 0.4318)
			(layers "F.Cu" "F.Mask" "F.Paste")
			(net "M_KLM_RST_N")
		)
		(pad "DV65" smd circle
			(at 19.221958 21.140674)
			(size 0.4318 0.4318)
			(layers "F.Cu" "F.Mask" "F.Paste")
			(net "M_L_ECC<2>")
		)
		(pad "DV67" smd circle
			(at 20.938998 21.140674)
			(size 0.4318 0.4318)
			(layers "F.Cu" "F.Mask" "F.Paste")
			(net "M_L_DQS_DN<17>")
		)
		(pad "DV69" smd circle
			(at 22.656038 21.140674)
			(size 0.4318 0.4318)
			(layers "F.Cu" "F.Mask" "F.Paste")
			(net "M_L_ECC<5>")
		)
		(pad "DV71" smd circle
			(at 24.373078 21.140674)
			(size 0.4318 0.4318)
			(layers "F.Cu" "F.Mask" "F.Paste")
			(net "TP_CPU1_RSVD_24")
		)
		(pad "DV73" smd circle
			(at 26.090118 21.140674)
			(size 0.4318 0.4318)
			(layers "F.Cu" "F.Mask" "F.Paste")
			(net "GND")
		)
		(pad "DV75" smd circle
			(at 27.806904 21.140674)
			(size 0.4318 0.4318)
			(layers "F.Cu" "F.Mask" "F.Paste")
			(net "M_K_DQS_DN<3>")
		)
		(pad "DV77" smd circle
			(at 29.523944 21.140674)
			(size 0.4318 0.4318)
			(layers "F.Cu" "F.Mask" "F.Paste")
			(net "GND")
		)
		(pad "DV79" smd circle
			(at 31.240984 21.140674)
			(size 0.4318 0.4318)
			(layers "F.Cu" "F.Mask" "F.Paste")
			(net "M_L_DQS_DP<11>")
		)
		(pad "DV81" smd circle
			(at 32.958024 21.140674)
			(size 0.4318 0.4318)
			(layers "F.Cu" "F.Mask" "F.Paste")
			(net "GND")
		)
		(pad "DV83" smd circle
			(at 34.675064 21.140674)
			(size 0.4318 0.4318)
			(layers "F.Cu" "F.Mask" "F.Paste")
			(net "M_K_DQ<10>")
		)
		(pad "DV85" smd custom
			(at 36.392104 21.140674 270)
			(size 0.10795 0.10795)
			(layers "F.Cu" "F.Mask" "F.Paste")
			(net "M_K_DQ<15>")
			(options
				(clearance outline)
				(anchor circle)
			)
			(primitives
				(gr_poly
					(pts
						(arc
							(start 0.2159 -0.0381)
							(mid 0 -0.254)
							(end -0.2159 -0.0381)
						)
						(arc
							(start -0.2159 0.0381)
							(mid 0 0.254)
							(end 0.2159 0.0381)
						)
					)
					(width 0)
					(fill yes)
				)
			)
		)
		(pad "DW2" smd custom
			(at -36.392104 23.436326 90)
			(size 0.10795 0.10795)
			(layers "F.Cu" "F.Mask" "F.Paste")
			(net "GND")
			(options
				(clearance outline)
				(anchor circle)
			)
			(primitives
				(gr_poly
					(pts
						(arc
							(start 0.2159 -0.0381)
							(mid 0 -0.254)
							(end -0.2159 -0.0381)
						)
						(arc
							(start -0.2159 0.0381)
							(mid 0 0.254)
							(end 0.2159 0.0381)
						)
					)
					(width 0)
					(fill yes)
				)
			)
		)
		(pad "DW4" smd circle
			(at -34.675064 23.436326)
			(size 0.4318 0.4318)
			(layers "F.Cu" "F.Mask" "F.Paste")
			(net "TP_P3E_CPU1_PE1_RSR3_TXN<10>")
		)
		(pad "DW6" smd circle
			(at -32.958024 23.436326)
			(size 0.4318 0.4318)
			(layers "F.Cu" "F.Mask" "F.Paste")
			(net "TP_P3E_CPU1_PE1_RSR3_TXP<13>")
		)
		(pad "DW8" smd circle
			(at -31.240984 23.436326)
			(size 0.4318 0.4318)
			(layers "F.Cu" "F.Mask" "F.Paste")
			(net "GND")
		)
		(pad "DW10" smd circle
			(at -29.523944 23.436326)
			(size 0.4318 0.4318)
			(layers "F.Cu" "F.Mask" "F.Paste")
			(net "P3E_CPU1_PE3_MP_TXN<5>")
		)
		(pad "DW12" smd circle
			(at -27.806904 23.436326)
			(size 0.4318 0.4318)
			(layers "F.Cu" "F.Mask" "F.Paste")
			(net "GND")
		)
		(pad "DW14" smd circle
			(at -26.090118 23.436326)
			(size 0.4318 0.4318)
			(layers "F.Cu" "F.Mask" "F.Paste")
			(net "TP_P3E_CPU1_PE1_RSR3_RXN<13>")
		)
		(pad "DW16" smd circle
			(at -24.373078 23.436326)
			(size 0.4318 0.4318)
			(layers "F.Cu" "F.Mask" "F.Paste")
			(net "P3E_CPU1_PE3_MP_RXN<2>")
		)
		(pad "DW18" smd circle
			(at -22.656038 23.436326)
			(size 0.4318 0.4318)
			(layers "F.Cu" "F.Mask" "F.Paste")
			(net "P3E_CPU1_PE3_MP_RXN<1>")
		)
		(pad "DW20" smd circle
			(at -20.938998 23.436326)
			(size 0.4318 0.4318)
			(layers "F.Cu" "F.Mask" "F.Paste")
			(net "GND")
		)
		(pad "DW22" smd circle
			(at -19.221958 23.436326)
			(size 0.4318 0.4318)
			(layers "F.Cu" "F.Mask" "F.Paste")
			(net "M_K_DQ<63>")
		)
		(pad "DW24" smd circle
			(at -17.504918 23.436326)
			(size 0.4318 0.4318)
			(layers "F.Cu" "F.Mask" "F.Paste")
			(net "GND")
		)
		(pad "DW26" smd circle
			(at -15.787878 23.436326)
			(size 0.4318 0.4318)
			(layers "F.Cu" "F.Mask" "F.Paste")
			(net "M_L_DQS_DP<15>")
		)
		(pad "DW28" smd circle
			(at -14.071092 23.436326)
			(size 0.4318 0.4318)
			(layers "F.Cu" "F.Mask" "F.Paste")
			(net "GND")
		)
		(pad "DW30" smd circle
			(at -12.354052 23.436326)
			(size 0.4318 0.4318)
			(layers "F.Cu" "F.Mask" "F.Paste")
			(net "GND")
		)
		(pad "DW32" smd circle
			(at -10.637012 23.436326)
			(size 0.4318 0.4318)
			(layers "F.Cu" "F.Mask" "F.Paste")
			(net "M_L_DQS_DP<14>")
		)
		(pad "DW34" smd circle
			(at -8.919972 23.436326)
			(size 0.4318 0.4318)
			(layers "F.Cu" "F.Mask" "F.Paste")
			(net "GND")
		)
		(pad "DW36" smd circle
			(at -7.202932 23.436326)
			(size 0.4318 0.4318)
			(layers "F.Cu" "F.Mask" "F.Paste")
			(net "GND")
		)
		(pad "DW38" smd circle
			(at -5.485892 23.436326)
			(size 0.4318 0.4318)
			(layers "F.Cu" "F.Mask" "F.Paste")
			(net "M_K_DQS_DP<13>")
		)
		(pad "DW40" smd circle
			(at -3.769106 23.436326)
			(size 0.4318 0.4318)
			(layers "F.Cu" "F.Mask" "F.Paste")
			(net "GND")
		)
		(pad "DW42" smd circle
			(at -2.052066 23.436326)
			(size 0.4318 0.4318)
			(layers "F.Cu" "F.Mask" "F.Paste")
			(net "M_L_DQ<33>")
		)
		(pad "DW44" smd circle
			(at 1.193546 21.636228)
			(size 0.508 0.508)
			(layers "F.Cu" "F.Mask" "F.Paste")
			(net "TP_CPU1_RSVD_23")
		)
		(pad "DW46" smd circle
			(at 2.910586 21.636228)
			(size 0.4318 0.4318)
			(layers "F.Cu" "F.Mask" "F.Paste")
			(net "TP_CPU1_RSVD_22")
		)
		(pad "DW48" smd circle
			(at 4.627626 21.636228)
			(size 0.4318 0.4318)
			(layers "F.Cu" "F.Mask" "F.Paste")
			(net "M_K_MA<13>")
		)
		(pad "DW50" smd circle
			(at 6.344412 21.636228)
			(size 0.4318 0.4318)
			(layers "F.Cu" "F.Mask" "F.Paste")
			(net "M_L_CS_N<4>")
		)
		(pad "DW52" smd circle
			(at 8.061452 21.636228)
			(size 0.4318 0.4318)
			(layers "F.Cu" "F.Mask" "F.Paste")
			(net "M_L_MA<0>")
		)
		(pad "DW54" smd circle
			(at 9.778492 21.636228)
			(size 0.4318 0.4318)
			(layers "F.Cu" "F.Mask" "F.Paste")
			(net "M_K_MA<10>")
		)
		(pad "DW56" smd circle
			(at 11.495532 21.636228)
			(size 0.4318 0.4318)
			(layers "F.Cu" "F.Mask" "F.Paste")
			(net "M_K_CLK_DN<2>")
		)
		(pad "DW58" smd circle
			(at 13.212572 21.636228)
			(size 0.4318 0.4318)
			(layers "F.Cu" "F.Mask" "F.Paste")
			(net "M_L_MA<1>")
		)
		(pad "DW60" smd circle
			(at 14.929612 21.636228)
			(size 0.4318 0.4318)
			(layers "F.Cu" "F.Mask" "F.Paste")
			(net "M_K_ACT_N")
		)
		(pad "DW62" smd circle
			(at 16.646398 21.636228)
			(size 0.4318 0.4318)
			(layers "F.Cu" "F.Mask" "F.Paste")
			(net "M_K_BG<1>")
		)
		(pad "DW64" smd circle
			(at 18.363438 21.636228)
			(size 0.4318 0.4318)
			(layers "F.Cu" "F.Mask" "F.Paste")
			(net "GND")
		)
		(pad "DW66" smd circle
			(at 20.080478 21.636228)
			(size 0.4318 0.4318)
			(layers "F.Cu" "F.Mask" "F.Paste")
			(net "GND")
		)
		(pad "DW68" smd circle
			(at 21.797518 21.636228)
			(size 0.4318 0.4318)
			(layers "F.Cu" "F.Mask" "F.Paste")
			(net "GND")
		)
		(pad "DW70" smd circle
			(at 23.514558 21.636228)
			(size 0.4318 0.4318)
			(layers "F.Cu" "F.Mask" "F.Paste")
			(net "GND")
		)
		(pad "DW72" smd circle
			(at 25.231598 21.636228)
			(size 0.4318 0.4318)
			(layers "F.Cu" "F.Mask" "F.Paste")
			(net "GND")
		)
		(pad "DW74" smd circle
			(at 26.948384 21.636228)
			(size 0.4318 0.4318)
			(layers "F.Cu" "F.Mask" "F.Paste")
			(net "GND")
		)
		(pad "DW76" smd circle
			(at 28.665424 21.636228)
			(size 0.4318 0.4318)
			(layers "F.Cu" "F.Mask" "F.Paste")
			(net "GND")
		)
		(pad "DW78" smd circle
			(at 30.382464 21.636228)
			(size 0.4318 0.4318)
			(layers "F.Cu" "F.Mask" "F.Paste")
			(net "M_L_DQ<22>")
		)
		(pad "DW80" smd circle
			(at 32.099504 21.636228)
			(size 0.4318 0.4318)
			(layers "F.Cu" "F.Mask" "F.Paste")
			(net "M_L_DQ<16>")
		)
		(pad "DW82" smd circle
			(at 33.816544 21.636228)
			(size 0.4318 0.4318)
			(layers "F.Cu" "F.Mask" "F.Paste")
			(net "GND")
		)
		(pad "DW84" smd circle
			(at 35.533584 21.636228)
			(size 0.4318 0.4318)
			(layers "F.Cu" "F.Mask" "F.Paste")
			(net "GND")
		)
		(pad "DY3" smd custom
			(at -35.533584 23.931626 135)
			(size 0.10795 0.10795)
			(layers "F.Cu" "F.Mask" "F.Paste")
			(net "TP_CPU1_RSVD_21")
			(options
				(clearance outline)
				(anchor circle)
			)
			(primitives
				(gr_poly
					(pts
						(arc
							(start 0.2159 -0.0381)
							(mid 0 -0.254)
							(end -0.2159 -0.0381)
						)
						(arc
							(start -0.2159 0.0381)
							(mid 0 0.254)
							(end 0.2159 0.0381)
						)
					)
					(width 0)
					(fill yes)
				)
			)
		)
		(pad "DY5" smd circle
			(at -33.816544 23.931626)
			(size 0.4318 0.4318)
			(layers "F.Cu" "F.Mask" "F.Paste")
			(net "GND")
		)
	)
)
